(kicad_pcb
	(version 20260206)
	(generator "pcbnew")
	(generator_version "10.0")
	(general
		(thickness 1.6)
		(legacy_teardrops no)
	)
	(paper "A4")
	(title_block
		(title "12092022_DA0F0TMDCD0_F0T_Management_Board_D_brd_V3_OCP.brd")
		(comment 1 "Grand Teton / footprint 804 of 1440 (GF1), pads 1-116 of 168")
	)
	(layers
		(0 "F.Cu" signal "TOP")
		(4 "In1.Cu" signal "GND")
		(6 "In2.Cu" signal "IN1")
		(8 "In3.Cu" signal "GND1")
		(10 "In4.Cu" signal "IN2")
		(12 "In5.Cu" signal "VCC")
		(14 "In6.Cu" signal "VCC1")
		(16 "In7.Cu" signal "IN3")
		(18 "In8.Cu" signal "GND2")
		(20 "In9.Cu" signal "IN4")
		(22 "In10.Cu" signal "GND3")
		(2 "B.Cu" signal "BOTTOM")
		(9 "F.Adhes" user "F.Adhesive")
		(11 "B.Adhes" user "B.Adhesive")
		(13 "F.Paste" user "Package Geometry/Pastemask Top")
		(15 "B.Paste" user "Package Geometry/Pastemask Bottom")
		(5 "F.SilkS" user "Ref Des/Silkscreen Top")
		(7 "B.SilkS" user "Ref Des/Silkscreen Bottom")
		(1 "F.Mask" user "Board Geometry/Soldermask Top")
		(3 "B.Mask" user "Board Geometry/Soldermask Bottom")
		(17 "Dwgs.User" user "User.Drawings")
		(19 "Cmts.User" user "User.Comments")
		(21 "Eco1.User" user "User.Eco1")
		(23 "Eco2.User" user "User.Eco2")
		(25 "Edge.Cuts" user "Board Geometry/Outline")
		(27 "Margin" user)
		(31 "F.CrtYd" user "Package Geometry/Place Bound Top")
		(29 "B.CrtYd" user "Package Geometry/Place Bound Bottom")
		(35 "F.Fab" user "Ref Des/Assembly Top")
		(33 "B.Fab" user "Ref Des/Assembly Bottom")
	)
	(footprint ""
		(layer "B.Cu")
		(at 45.260006 -114.324892 180)
		(property "Reference" "GF1"
			(at 30.591506 -4.763262 0)
			(unlocked yes)
			(layer "B.SilkS")
			(effects
				(font
					(size 0.7874 0.5842)
					(thickness 0.1524)
				)
				(justify left mirror)
			)
		)
		(property "Value" ""
			(at 0 0 0)
			(layer "B.Fab")
			(effects
				(font
					(size 1.27 1.27)
				)
				(justify mirror)
			)
		)
		(duplicate_pad_numbers_are_jumpers no)
		(pad "A1" smd rect
			(at -18.204942 4.13512)
			(size 0.381 2.1336)
			(layers "B.Cu" "B.Mask" "B.Paste")
			(net "SMB_BMC_MM14_R1_SCL")
		)
		(pad "A2" smd rect
			(at -17.604994 4.13512)
			(size 0.381 2.1336)
			(layers "B.Cu" "B.Mask" "B.Paste")
			(net "SMB_BMC_MM14_R1_SDA")
		)
		(pad "A3" smd rect
			(at -17.005046 4.13512)
			(size 0.381 2.1336)
			(layers "B.Cu" "B.Mask" "B.Paste")
			(net "SMB_BMC_MM1_SCL")
		)
		(pad "A4" smd rect
			(at -16.405098 4.13512)
			(size 0.381 2.1336)
			(layers "B.Cu" "B.Mask" "B.Paste")
			(net "SMB_BMC_MM1_SDA")
		)
		(pad "A5" smd rect
			(at -15.804896 4.13512)
			(size 0.381 2.1336)
			(layers "B.Cu" "B.Mask" "B.Paste")
			(net "SMB_BMC_MM2_SCL_R1")
		)
		(pad "A6" smd rect
			(at -15.204948 4.13512)
			(size 0.381 2.1336)
			(layers "B.Cu" "B.Mask" "B.Paste")
			(net "SMB_BMC_MM2_SDA")
		)
		(pad "A7" smd rect
			(at -14.605 3.934968)
			(size 0.381 1.7272)
			(layers "B.Cu" "B.Mask" "B.Paste")
			(net "SMB_BMC_MM3_SCL")
		)
		(pad "A8" smd rect
			(at -14.005052 3.934968)
			(size 0.381 1.7272)
			(layers "B.Cu" "B.Mask" "B.Paste")
			(net "SMB_BMC_MM3_SDA")
		)
		(pad "A9" smd rect
			(at -13.405104 3.934968)
			(size 0.381 1.7272)
			(layers "B.Cu" "B.Mask" "B.Paste")
			(net "SMB_BMC_MM4_SCL")
		)
		(pad "A10" smd rect
			(at -12.804902 3.934968)
			(size 0.381 1.7272)
			(layers "B.Cu" "B.Mask" "B.Paste")
			(net "SMB_BMC_MM4_SDA")
		)
		(pad "A11" smd rect
			(at -12.204954 3.934968)
			(size 0.381 1.7272)
			(layers "B.Cu" "B.Mask" "B.Paste")
			(net "SMB_BMC_MM5_SCL")
		)
		(pad "A12" smd rect
			(at -11.605006 3.934968)
			(size 0.381 1.7272)
			(layers "B.Cu" "B.Mask" "B.Paste")
			(net "SMB_BMC_MM5_SDA")
		)
		(pad "A13" smd rect
			(at -11.005058 4.13512)
			(size 0.381 2.1336)
			(layers "B.Cu" "B.Mask" "B.Paste")
			(net "GND")
		)
		(pad "A14" smd rect
			(at -10.40511 3.934968)
			(size 0.381 1.7272)
			(layers "B.Cu" "B.Mask" "B.Paste")
			(net "CLK_100M_PCH_DP")
		)
		(pad "A15" smd rect
			(at -9.804908 3.934968)
			(size 0.381 1.7272)
			(layers "B.Cu" "B.Mask" "B.Paste")
			(net "CLK_100M_PCH_DN")
		)
		(pad "A16" smd rect
			(at -9.20496 4.13512)
			(size 0.381 2.1336)
			(layers "B.Cu" "B.Mask" "B.Paste")
			(net "GND")
		)
		(pad "A17" smd rect
			(at -8.605012 3.934968)
			(size 0.381 1.7272)
			(layers "B.Cu" "B.Mask" "B.Paste")
			(net "P2E_PCH_RX_DP")
		)
		(pad "A18" smd rect
			(at -8.005064 3.934968)
			(size 0.381 1.7272)
			(layers "B.Cu" "B.Mask" "B.Paste")
			(net "P2E_PCH_RX_DN")
		)
		(pad "A19" smd rect
			(at -7.405116 4.13512)
			(size 0.381 2.1336)
			(layers "B.Cu" "B.Mask" "B.Paste")
			(net "GND")
		)
		(pad "A20" smd rect
			(at -6.804914 3.934968)
			(size 0.381 1.7272)
			(layers "B.Cu" "B.Mask" "B.Paste")
			(net "P2E_PCH_TX_C_DP")
		)
		(pad "A21" smd rect
			(at -6.204966 3.934968)
			(size 0.381 1.7272)
			(layers "B.Cu" "B.Mask" "B.Paste")
			(net "P2E_PCH_TX_C_DN")
		)
		(pad "A22" smd rect
			(at -5.605018 4.13512)
			(size 0.381 2.1336)
			(layers "B.Cu" "B.Mask" "B.Paste")
			(net "GND")
		)
		(pad "A23" smd rect
			(at -5.00507 3.934968)
			(size 0.381 1.7272)
			(layers "B.Cu" "B.Mask" "B.Paste")
			(net "SMB_BMC_MM6_SCL")
		)
		(pad "A24" smd rect
			(at -4.405122 3.934968)
			(size 0.381 1.7272)
			(layers "B.Cu" "B.Mask" "B.Paste")
			(net "SMB_BMC_MM6_SDA")
		)
		(pad "A25" smd rect
			(at -3.80492 4.13512)
			(size 0.381 2.1336)
			(layers "B.Cu" "B.Mask" "B.Paste")
			(net "SMB_BMC_MM7_SCL")
		)
		(pad "A26" smd rect
			(at -3.204972 3.934968)
			(size 0.381 1.7272)
			(layers "B.Cu" "B.Mask" "B.Paste")
			(net "SMB_BMC_MM7_SDA")
		)
		(pad "A27" smd rect
			(at -2.605024 3.934968)
			(size 0.381 1.7272)
			(layers "B.Cu" "B.Mask" "B.Paste")
			(net "SMB_BMC_MM8_SCL")
		)
		(pad "A28" smd rect
			(at -2.005076 4.13512)
			(size 0.381 2.1336)
			(layers "B.Cu" "B.Mask" "B.Paste")
			(net "SMB_BMC_MM8_SDA")
		)
		(pad "A29" smd rect
			(at 2.005076 4.13512)
			(size 0.381 2.1336)
			(layers "B.Cu" "B.Mask" "B.Paste")
			(net "SMB_BMC_MM9_SCL")
		)
		(pad "A30" smd rect
			(at 2.605024 3.934968)
			(size 0.381 1.7272)
			(layers "B.Cu" "B.Mask" "B.Paste")
			(net "SMB_BMC_MM9_SDA")
		)
		(pad "A31" smd rect
			(at 3.204972 3.934968)
			(size 0.381 1.7272)
			(layers "B.Cu" "B.Mask" "B.Paste")
			(net "SMB_BMC_MM10_SCL")
		)
		(pad "A32" smd rect
			(at 3.80492 4.13512)
			(size 0.381 2.1336)
			(layers "B.Cu" "B.Mask" "B.Paste")
			(net "SMB_BMC_MM10_SDA")
		)
		(pad "A33" smd rect
			(at 4.405122 3.934968)
			(size 0.381 1.7272)
			(layers "B.Cu" "B.Mask" "B.Paste")
			(net "GND")
		)
		(pad "A34" smd rect
			(at 5.00507 3.934968)
			(size 0.381 1.7272)
			(layers "B.Cu" "B.Mask" "B.Paste")
			(net "JTAG_MB_TCK")
		)
		(pad "A35" smd rect
			(at 5.605018 4.13512)
			(size 0.381 2.1336)
			(layers "B.Cu" "B.Mask" "B.Paste")
			(net "JTAG_MB_TMS")
		)
		(pad "A36" smd rect
			(at 6.204966 3.934968)
			(size 0.381 1.7272)
			(layers "B.Cu" "B.Mask" "B.Paste")
			(net "JTAG_MB_TDI")
		)
		(pad "A37" smd rect
			(at 6.804914 3.934968)
			(size 0.381 1.7272)
			(layers "B.Cu" "B.Mask" "B.Paste")
			(net "JTAG_MB_TDO")
		)
		(pad "A38" smd rect
			(at 7.405116 4.13512)
			(size 0.381 2.1336)
			(layers "B.Cu" "B.Mask" "B.Paste")
			(net "SMB_BMC_MM12_SCL")
		)
		(pad "A39" smd rect
			(at 8.005064 3.934968)
			(size 0.381 1.7272)
			(layers "B.Cu" "B.Mask" "B.Paste")
			(net "SMB_BMC_MM12_SDA")
		)
		(pad "A40" smd rect
			(at 8.605012 3.934968)
			(size 0.381 1.7272)
			(layers "B.Cu" "B.Mask" "B.Paste")
			(net "SMB_BMC_MM13_SCL")
		)
		(pad "A41" smd rect
			(at 9.20496 4.13512)
			(size 0.381 2.1336)
			(layers "B.Cu" "B.Mask" "B.Paste")
			(net "SMB_BMC_MM13_SDA")
		)
		(pad "A42" smd rect
			(at 9.804908 4.13512)
			(size 0.381 2.1336)
			(layers "B.Cu" "B.Mask" "B.Paste")
			(net "GND")
		)
		(pad "A43" smd rect
			(at 14.714982 4.13512)
			(size 0.381 2.1336)
			(layers "B.Cu" "B.Mask" "B.Paste")
			(net "FM_JTAG_SEL")
		)
		(pad "A44" smd rect
			(at 15.31493 3.934968)
			(size 0.381 1.7272)
			(layers "B.Cu" "B.Mask" "B.Paste")
			(net "PWRGD_PSU_AC_PWROK_R")
		)
		(pad "A45" smd rect
			(at 15.914878 3.934968)
			(size 0.381 1.7272)
			(layers "B.Cu" "B.Mask" "B.Paste")
			(net "TP_GF_A45")
		)
		(pad "A46" smd rect
			(at 16.51508 4.13512)
			(size 0.381 2.1336)
			(layers "B.Cu" "B.Mask" "B.Paste")
			(net "RST_MB_STBY_N")
		)
		(pad "A47" smd rect
			(at 17.115028 3.934968)
			(size 0.381 1.7272)
			(layers "B.Cu" "B.Mask" "B.Paste")
			(net "SYS_PWRBTN_N")
		)
		(pad "A48" smd rect
			(at 17.714976 3.934968)
			(size 0.381 1.7272)
			(layers "B.Cu" "B.Mask" "B.Paste")
			(net "PWRGD_SYS_PWROK")
		)
		(pad "A49" smd rect
			(at 18.314924 4.13512)
			(size 0.381 2.1336)
			(layers "B.Cu" "B.Mask" "B.Paste")
			(net "FM_DBP_CPU_PREQ_GF_R_N")
		)
		(pad "A50" smd rect
			(at 18.914872 3.934968)
			(size 0.381 1.7272)
			(layers "B.Cu" "B.Mask" "B.Paste")
			(net "FM_DBP_BMC_PRDY_N")
		)
		(pad "A51" smd rect
			(at 19.515074 3.934968)
			(size 0.381 1.7272)
			(layers "B.Cu" "B.Mask" "B.Paste")
			(net "RST_PLTRST_N")
		)
		(pad "A52" smd rect
			(at 20.115022 4.13512)
			(size 0.381 2.1336)
			(layers "B.Cu" "B.Mask" "B.Paste")
			(net "FM_BMC_UARTSW_MSB_N")
		)
		(pad "A53" smd rect
			(at 20.71497 3.934968)
			(size 0.381 1.7272)
			(layers "B.Cu" "B.Mask" "B.Paste")
			(net "RST_ROT_CPU_N")
		)
		(pad "A54" smd rect
			(at 21.314918 3.934968)
			(size 0.381 1.7272)
			(layers "B.Cu" "B.Mask" "B.Paste")
			(net "FM_INTRUDER_N")
		)
		(pad "A55" smd rect
			(at 21.91512 4.13512)
			(size 0.381 2.1336)
			(layers "B.Cu" "B.Mask" "B.Paste")
			(net "FM_BMC_UARTSW_LSB_N")
		)
		(pad "A56" smd rect
			(at 22.515068 3.934968)
			(size 0.381 1.7272)
			(layers "B.Cu" "B.Mask" "B.Paste")
			(net "IRQ_SMI_ACTIVE_GF_N")
		)
		(pad "A57" smd rect
			(at 23.115016 3.934968)
			(size 0.381 1.7272)
			(layers "B.Cu" "B.Mask" "B.Paste")
			(net "FM_PRSNT_1_N")
		)
		(pad "A58" smd rect
			(at 23.714964 4.13512)
			(size 0.381 2.1336)
			(layers "B.Cu" "B.Mask" "B.Paste")
			(net "GND")
		)
		(pad "A59" smd rect
			(at 24.314912 3.934968)
			(size 0.381 1.7272)
			(layers "B.Cu" "B.Mask" "B.Paste")
			(net "USB3_FPNL_RXP")
		)
		(pad "A60" smd rect
			(at 24.915114 3.934968)
			(size 0.381 1.7272)
			(layers "B.Cu" "B.Mask" "B.Paste")
			(net "USB3_FPNL_RXN")
		)
		(pad "A61" smd rect
			(at 25.515062 4.13512)
			(size 0.381 2.1336)
			(layers "B.Cu" "B.Mask" "B.Paste")
			(net "GND")
		)
		(pad "A62" smd rect
			(at 26.11501 3.934968)
			(size 0.381 1.7272)
			(layers "B.Cu" "B.Mask" "B.Paste")
			(net "TP_GF_A62")
		)
		(pad "A63" smd rect
			(at 26.714958 3.934968)
			(size 0.381 1.7272)
			(layers "B.Cu" "B.Mask" "B.Paste")
			(net "TP_GF_A63")
		)
		(pad "A64" smd rect
			(at 27.314906 4.13512)
			(size 0.381 2.1336)
			(layers "B.Cu" "B.Mask" "B.Paste")
			(net "GND")
		)
		(pad "A65" smd rect
			(at 27.915108 3.934968)
			(size 0.381 1.7272)
			(layers "B.Cu" "B.Mask" "B.Paste")
			(net "P2E_GPU_RX_DP")
		)
		(pad "A66" smd rect
			(at 28.515056 3.934968)
			(size 0.381 1.7272)
			(layers "B.Cu" "B.Mask" "B.Paste")
			(net "P2E_GPU_RX_DN")
		)
		(pad "A67" smd rect
			(at 29.115004 4.13512)
			(size 0.381 2.1336)
			(layers "B.Cu" "B.Mask" "B.Paste")
			(net "GND")
		)
		(pad "A68" smd rect
			(at 29.714952 3.934968)
			(size 0.381 1.7272)
			(layers "B.Cu" "B.Mask" "B.Paste")
			(net "CLK_100M_GPU_DP")
		)
		(pad "A69" smd rect
			(at 30.3149 3.934968)
			(size 0.381 1.7272)
			(layers "B.Cu" "B.Mask" "B.Paste")
			(net "CLK_100M_GPU_DN")
		)
		(pad "A70" smd rect
			(at 30.915102 4.13512)
			(size 0.381 2.1336)
			(layers "B.Cu" "B.Mask" "B.Paste")
			(net "GND")
		)
		(pad "B1" smd rect
			(at -18.204942 3.934968)
			(size 0.381 1.7272)
			(layers "B.Cu" "B.Mask" "B.Paste")
			(net "ESPI_HOST_LPC_BMC_CLK")
		)
		(pad "B2" smd rect
			(at -17.604994 3.934968)
			(size 0.381 1.7272)
			(layers "B.Cu" "B.Mask" "B.Paste")
			(net "ESPI_HOST_LPC_BMC_LFRAME_N")
		)
		(pad "B3" smd rect
			(at -17.005046 3.934968)
			(size 0.381 1.7272)
			(layers "B.Cu" "B.Mask" "B.Paste")
			(net "IRQ_BMC_LPC_SERIRQ_ESPI_GF")
		)
		(pad "B4" smd rect
			(at -16.405098 3.934968)
			(size 0.381 1.7272)
			(layers "B.Cu" "B.Mask" "B.Paste")
			(net "RST_BMC_LPC_ESPI_N")
		)
		(pad "B5" smd rect
			(at -15.804896 3.934968)
			(size 0.381 1.7272)
			(layers "B.Cu" "B.Mask" "B.Paste")
			(net "ESPI_LPC_LAD0_IO0")
		)
		(pad "B6" smd rect
			(at -15.204948 3.934968)
			(size 0.381 1.7272)
			(layers "B.Cu" "B.Mask" "B.Paste")
			(net "ESPI_LPC_LAD1_IO1")
		)
		(pad "B7" smd rect
			(at -14.605 3.934968)
			(size 0.381 1.7272)
			(layers "B.Cu" "B.Mask" "B.Paste")
			(net "ESPI_LPC_LAD2_IO2")
		)
		(pad "B8" smd rect
			(at -14.005052 3.934968)
			(size 0.381 1.7272)
			(layers "B.Cu" "B.Mask" "B.Paste")
			(net "ESPI_LPC_LAD3_IO3")
		)
		(pad "B9" smd rect
			(at -13.405104 3.934968)
			(size 0.381 1.7272)
			(layers "B.Cu" "B.Mask" "B.Paste")
			(net "LPC_ESPI_SEL")
		)
		(pad "B10" smd rect
			(at -12.804902 3.934968)
			(size 0.381 1.7272)
			(layers "B.Cu" "B.Mask" "B.Paste")
			(net "GND")
		)
		(pad "B11" smd rect
			(at -12.204954 3.934968)
			(size 0.381 1.7272)
			(layers "B.Cu" "B.Mask" "B.Paste")
			(net "SPI_SYS_R_CLK")
		)
		(pad "B12" smd rect
			(at -11.605006 3.934968)
			(size 0.381 1.7272)
			(layers "B.Cu" "B.Mask" "B.Paste")
			(net "SPI_SYS_CS0_N")
		)
		(pad "B13" smd rect
			(at -11.005058 4.13512)
			(size 0.381 2.1336)
			(layers "B.Cu" "B.Mask" "B.Paste")
			(net "SPI_SYS_R_MOSI")
		)
		(pad "B14" smd rect
			(at -10.40511 3.934968)
			(size 0.381 1.7272)
			(layers "B.Cu" "B.Mask" "B.Paste")
			(net "SPI_SYS_R_MISO")
		)
		(pad "B15" smd rect
			(at -9.804908 3.934968)
			(size 0.381 1.7272)
			(layers "B.Cu" "B.Mask" "B.Paste")
			(net "SPI_SYS_WP_R_IO2")
		)
		(pad "B16" smd rect
			(at -9.20496 4.13512)
			(size 0.381 2.1336)
			(layers "B.Cu" "B.Mask" "B.Paste")
			(net "SPI_SYS_HOLD_R_IO3")
		)
		(pad "B17" smd rect
			(at -8.605012 3.934968)
			(size 0.381 1.7272)
			(layers "B.Cu" "B.Mask" "B.Paste")
			(net "GND")
		)
		(pad "B18" smd rect
			(at -8.005064 3.934968)
			(size 0.381 1.7272)
			(layers "B.Cu" "B.Mask" "B.Paste")
			(net "RMII_OCP_RCLKI")
		)
		(pad "B19" smd rect
			(at -7.405116 4.13512)
			(size 0.381 2.1336)
			(layers "B.Cu" "B.Mask" "B.Paste")
			(net "RMII_CSRDV")
		)
		(pad "B20" smd rect
			(at -6.804914 3.934968)
			(size 0.381 1.7272)
			(layers "B.Cu" "B.Mask" "B.Paste")
			(net "RMII_TXEN")
		)
		(pad "B21" smd rect
			(at -6.204966 3.934968)
			(size 0.381 1.7272)
			(layers "B.Cu" "B.Mask" "B.Paste")
			(net "RMII_TXD0")
		)
		(pad "B22" smd rect
			(at -5.605018 4.13512)
			(size 0.381 2.1336)
			(layers "B.Cu" "B.Mask" "B.Paste")
			(net "RMII_TXD1")
		)
		(pad "B23" smd rect
			(at -5.00507 3.934968)
			(size 0.381 1.7272)
			(layers "B.Cu" "B.Mask" "B.Paste")
			(net "RMII_RXER")
		)
		(pad "B24" smd rect
			(at -4.405122 3.934968)
			(size 0.381 1.7272)
			(layers "B.Cu" "B.Mask" "B.Paste")
			(net "RMII_RXD0")
		)
		(pad "B25" smd rect
			(at -3.80492 4.13512)
			(size 0.381 2.1336)
			(layers "B.Cu" "B.Mask" "B.Paste")
			(net "RMII_RXD1")
		)
		(pad "B26" smd rect
			(at -3.204972 3.934968)
			(size 0.381 1.7272)
			(layers "B.Cu" "B.Mask" "B.Paste")
			(net "GND")
		)
		(pad "B27" smd rect
			(at -2.605024 3.934968)
			(size 0.381 1.7272)
			(layers "B.Cu" "B.Mask" "B.Paste")
			(net "PECI_BMC")
		)
		(pad "B28" smd rect
			(at -2.005076 4.13512)
			(size 0.381 2.1336)
			(layers "B.Cu" "B.Mask" "B.Paste")
			(net "PVCCIO_PECI_BMC")
		)
		(pad "B29" smd rect
			(at 2.005076 4.13512)
			(size 0.381 2.1336)
			(layers "B.Cu" "B.Mask" "B.Paste")
			(net "SGPIO_DO_0")
		)
		(pad "B30" smd rect
			(at 2.605024 3.934968)
			(size 0.381 1.7272)
			(layers "B.Cu" "B.Mask" "B.Paste")
			(net "SGPIO_CLK_0")
		)
		(pad "B31" smd rect
			(at 3.204972 3.934968)
			(size 0.381 1.7272)
			(layers "B.Cu" "B.Mask" "B.Paste")
			(net "SGPIO_DI_0")
		)
		(pad "B32" smd rect
			(at 3.80492 4.13512)
			(size 0.381 2.1336)
			(layers "B.Cu" "B.Mask" "B.Paste")
			(net "SGPIO_LD_0")
		)
		(pad "B33" smd rect
			(at 4.405122 3.934968)
			(size 0.381 1.7272)
			(layers "B.Cu" "B.Mask" "B.Paste")
			(net "GND")
		)
		(pad "B34" smd rect
			(at 5.00507 3.934968)
			(size 0.381 1.7272)
			(layers "B.Cu" "B.Mask" "B.Paste")
			(net "SGPIO_DO_1")
		)
		(pad "B35" smd rect
			(at 5.605018 4.13512)
			(size 0.381 2.1336)
			(layers "B.Cu" "B.Mask" "B.Paste")
			(net "SGPIO_CLK_1")
		)
		(pad "B36" smd rect
			(at 6.204966 3.934968)
			(size 0.381 1.7272)
			(layers "B.Cu" "B.Mask" "B.Paste")
			(net "SGPIO_DI_1")
		)
		(pad "B37" smd rect
			(at 6.804914 3.934968)
			(size 0.381 1.7272)
			(layers "B.Cu" "B.Mask" "B.Paste")
			(net "SGPIO_LD_1")
		)
		(pad "B38" smd rect
			(at 7.405116 4.13512)
			(size 0.381 2.1336)
			(layers "B.Cu" "B.Mask" "B.Paste")
			(net "GND")
		)
		(pad "B39" smd rect
			(at 8.005064 3.934968)
			(size 0.381 1.7272)
			(layers "B.Cu" "B.Mask" "B.Paste")
			(net "RST_SGPIO_RESET_N")
		)
		(pad "B40" smd rect
			(at 8.605012 3.934968)
			(size 0.381 1.7272)
			(layers "B.Cu" "B.Mask" "B.Paste")
			(net "IRQ_SGPIO_N")
		)
		(pad "B41" smd rect
			(at 9.20496 4.13512)
			(size 0.381 2.1336)
			(layers "B.Cu" "B.Mask" "B.Paste")
			(net "P3V_BAT_R")
		)
		(pad "B42" smd rect
			(at 9.804908 4.13512)
			(size 0.381 2.1336)
			(layers "B.Cu" "B.Mask" "B.Paste")
			(net "AC_PWR_BTN_N")
		)
		(pad "B43" smd rect
			(at 14.714982 4.13512)
			(size 0.381 2.1336)
			(layers "B.Cu" "B.Mask" "B.Paste")
			(net "QSPI_2_PLD_CLK")
		)
		(pad "B44" smd rect
			(at 15.31493 3.934968)
			(size 0.381 1.7272)
			(layers "B.Cu" "B.Mask" "B.Paste")
			(net "TP_GF1_B44")
		)
		(pad "B45" smd rect
			(at 15.914878 3.934968)
			(size 0.381 1.7272)
			(layers "B.Cu" "B.Mask" "B.Paste")
			(net "QSPI_2_PLD_IO0")
		)
		(pad "B46" smd rect
			(at 16.51508 4.13512)
			(size 0.381 2.1336)
			(layers "B.Cu" "B.Mask" "B.Paste")
			(net "QSPI_2_PLD_IO1")
		)
	)
)
